# T6G (Grand Teton) — schematic netlist excerpt (pin names and nets, part order shuffled) for the footprints in the layout excerpt that follows; sources: Cadence DE-HDL packaged netlist, KiCad conversion of 04192023_DAF0TMB3IC0_F0TG_MB_C_brd_V02_OCP.brd

Q145  MOSFET_NCH_DUAL  PJT138K IC  pkg SOT363XD  page 241
  S1  = GND
  G1  = HPDB_HSC_PWRGD
  D2  = HPDB_HSC_PWRGD_ISO
  S2  = GND
  G2  = HPDB_HSC_PWRGD_N
  D1  = HPDB_HSC_PWRGD_N

C593  Q_CAP  0.1UF 25V 10% X7R  pkg 0402  page 134 : A = P3V3_AUX ; B = GND
R1070  Q_RES  10K 1% CHIP  pkg 0201LF  page 298 : A = GPIO2_RT_CPU0_P2 ; B = GND

(kicad_pcb
	(version 20260206)
	(generator "pcbnew")
	(generator_version "10.0")
	(general
		(thickness 1.6)
		(legacy_teardrops no)
	)
	(paper "A4")
	(title_block
		(title "04192023_DAF0TMB3IC0_F0TG_MB_C_brd_V02_OCP.brd")
		(comment 1 "Grand Teton / footprints 413-415 of 8354")
	)
	(layers
		(0 "F.Cu" signal "TOP")
		(4 "In1.Cu" signal "GND")
		(6 "In2.Cu" signal "IN1")
		(8 "In3.Cu" signal "GND1")
		(10 "In4.Cu" signal "IN2")
		(12 "In5.Cu" signal "GND2")
		(14 "In6.Cu" signal "IN3")
		(16 "In7.Cu" signal "GND3")
		(18 "In8.Cu" signal "VCC")
		(20 "In9.Cu" signal "VCC1")
		(22 "In10.Cu" signal "GND4")
		(24 "In11.Cu" signal "IN4")
		(26 "In12.Cu" signal "GND5")
		(28 "In13.Cu" signal "IN5")
		(30 "In14.Cu" signal "GND6")
		(32 "In15.Cu" signal "IN6")
		(34 "In16.Cu" signal "GND7")
		(2 "B.Cu" signal "BOTTOM")
		(9 "F.Adhes" user "F.Adhesive")
		(11 "B.Adhes" user "B.Adhesive")
		(13 "F.Paste" user "Package Geometry/Pastemask Top")
		(15 "B.Paste" user "Package Geometry/Pastemask Bottom")
		(5 "F.SilkS" user "Ref Des/Silkscreen Top")
		(7 "B.SilkS" user "Ref Des/Silkscreen Bottom")
		(1 "F.Mask" user "Board Geometry/Soldermask Top")
		(3 "B.Mask" user "Board Geometry/Soldermask Bottom")
		(17 "Dwgs.User" user "User.Drawings")
		(19 "Cmts.User" user "User.Comments")
		(21 "Eco1.User" user "User.Eco1")
		(23 "Eco2.User" user "User.Eco2")
		(25 "Edge.Cuts" user "Board Geometry/Outline")
		(27 "Margin" user)
		(31 "F.CrtYd" user "Package Geometry/Place Bound Top")
		(29 "B.CrtYd" user "Package Geometry/Place Bound Bottom")
		(35 "F.Fab" user "Ref Des/Assembly Top")
		(33 "B.Fab" user "Ref Des/Assembly Bottom")
	)
	(footprint ""
		(layer "F.Cu")
		(at 461.720946 -103.614728)
		(property "Reference" "C593"
			(at 0 0 0)
			(layer "F.SilkS")
			(hide yes)
			(effects
				(font
					(size 1.27 1.27)
				)
			)
		)
		(property "Value" ""
			(at 0 0 0)
			(layer "F.Fab")
			(effects
				(font
					(size 1.27 1.27)
				)
			)
		)
		(duplicate_pad_numbers_are_jumpers no)
		(fp_line
			(start -0.7874 -0.4064)
			(end 0.7874 -0.4064)
			(stroke
				(width 0.1524)
				(type default)
			)
			(layer "F.SilkS")
		)
		(fp_line
			(start -0.7874 0.4064)
			(end -0.7874 -0.4064)
			(stroke
				(width 0.1524)
				(type default)
			)
			(layer "F.SilkS")
		)
		(fp_line
			(start 0.7874 -0.4064)
			(end 0.7874 0.4064)
			(stroke
				(width 0.1524)
				(type default)
			)
			(layer "F.SilkS")
		)
		(fp_line
			(start 0.7874 0.4064)
			(end -0.7874 0.4064)
			(stroke
				(width 0.1524)
				(type default)
			)
			(layer "F.SilkS")
		)
		(fp_line
			(start -0.67945 -0.305054)
			(end -0.12065 -0.305054)
			(stroke
				(width 0.1)
				(type default)
			)
			(layer "F.Fab")
		)
		(fp_line
			(start -0.67945 0.3048)
			(end -0.67945 -0.305054)
			(stroke
				(width 0.1)
				(type default)
			)
			(layer "F.Fab")
		)
		(fp_line
			(start -0.12065 -0.305054)
			(end -0.12065 -0.2794)
			(stroke
				(width 0.1)
				(type default)
			)
			(layer "F.Fab")
		)
		(fp_line
			(start -0.12065 -0.2794)
			(end 0.12065 -0.2794)
			(stroke
				(width 0.1)
				(type default)
			)
			(layer "F.Fab")
		)
		(fp_line
			(start -0.12065 0.2794)
			(end -0.12065 0.3048)
			(stroke
				(width 0.1)
				(type default)
			)
			(layer "F.Fab")
		)
		(fp_line
			(start -0.12065 0.3048)
			(end -0.67945 0.3048)
			(stroke
				(width 0.1)
				(type default)
			)
			(layer "F.Fab")
		)
		(fp_line
			(start 0.120396 0.2794)
			(end -0.12065 0.2794)
			(stroke
				(width 0.1)
				(type default)
			)
			(layer "F.Fab")
		)
		(fp_line
			(start 0.120396 0.3048)
			(end 0.120396 0.2794)
			(stroke
				(width 0.1)
				(type default)
			)
			(layer "F.Fab")
		)
		(fp_line
			(start 0.12065 -0.3048)
			(end 0.67945 -0.3048)
			(stroke
				(width 0.1)
				(type default)
			)
			(layer "F.Fab")
		)
		(fp_line
			(start 0.12065 -0.2794)
			(end 0.12065 -0.3048)
			(stroke
				(width 0.1)
				(type default)
			)
			(layer "F.Fab")
		)
		(fp_line
			(start 0.67945 -0.3048)
			(end 0.67945 0.3048)
			(stroke
				(width 0.1)
				(type default)
			)
			(layer "F.Fab")
		)
		(fp_line
			(start 0.67945 0.3048)
			(end 0.120396 0.3048)
			(stroke
				(width 0.1)
				(type default)
			)
			(layer "F.Fab")
		)
		(pad "1" smd circle
			(at -0.40005 0)
			(size 0 0)
			(layers "F.Cu" "F.Mask" "F.Paste")
			(net "P3V3_AUX")
		)
		(pad "2" smd circle
			(at 0.40005 0)
			(size 0 0)
			(layers "F.Cu" "F.Mask" "F.Paste")
			(net "GND")
		)
	)
	(footprint ""
		(layer "F.Cu")
		(at 282.133294 -437.2737)
		(property "Reference" "Q145"
			(at -1.4224 -1.768348 0)
			(unlocked yes)
			(layer "F.SilkS")
			(effects
				(font
					(size 0.7874 0.5842)
					(thickness 0.1524)
				)
				(justify left)
			)
		)
		(property "Value" ""
			(at 0 0 0)
			(layer "F.Fab")
			(effects
				(font
					(size 1.27 1.27)
				)
			)
		)
		(duplicate_pad_numbers_are_jumpers no)
		(fp_line
			(start -1.332738 -1.100074)
			(end -0.4826 -1.100074)
			(stroke
				(width 0.1524)
				(type default)
			)
			(layer "F.SilkS")
		)
		(fp_line
			(start -1.332738 1.100074)
			(end -1.332738 -1.100074)
			(stroke
				(width 0.1524)
				(type default)
			)
			(layer "F.SilkS")
		)
		(fp_line
			(start -0.4826 -1.100074)
			(end 0 -0.541274)
			(stroke
				(width 0.1524)
				(type default)
			)
			(layer "F.SilkS")
		)
		(fp_line
			(start 0 -0.541274)
			(end 0.4826 -1.100074)
			(stroke
				(width 0.1524)
				(type default)
			)
			(layer "F.SilkS")
		)
		(fp_line
			(start 0.4826 -1.100074)
			(end 1.332738 -1.100074)
			(stroke
				(width 0.1524)
				(type default)
			)
			(layer "F.SilkS")
		)
		(fp_line
			(start 1.332738 -1.100074)
			(end 1.332738 1.100074)
			(stroke
				(width 0.1524)
				(type default)
			)
			(layer "F.SilkS")
		)
		(fp_line
			(start 1.332738 1.100074)
			(end -1.332738 1.100074)
			(stroke
				(width 0.1524)
				(type default)
			)
			(layer "F.SilkS")
		)
		(fp_poly
			(pts
				(xy -2.252726 -1.230376) (xy -1.756156 -1.726946) (xy -1.507998 -0.982218)
			)
			(stroke
				(width 0)
				(type default)
			)
			(fill yes)
			(layer "F.SilkS")
		)
		(fp_line
			(start -0.674878 -1.100074)
			(end 0.674878 -1.100074)
			(stroke
				(width 0.1)
				(type default)
			)
			(layer "F.Fab")
		)
		(fp_line
			(start -0.674878 1.100074)
			(end -0.674878 -1.100074)
			(stroke
				(width 0.1)
				(type default)
			)
			(layer "F.Fab")
		)
		(fp_line
			(start 0.674878 -1.100074)
			(end 0.674878 1.100074)
			(stroke
				(width 0.1)
				(type default)
			)
			(layer "F.Fab")
		)
		(fp_line
			(start 0.674878 1.100074)
			(end -0.674878 1.100074)
			(stroke
				(width 0.1)
				(type default)
			)
			(layer "F.Fab")
		)
		(fp_poly
			(pts
				(xy -2.2352 -0.298958) (xy -2.2352 -1.001014) (xy -1.533144 -0.649986)
			)
			(stroke
				(width 0)
				(type default)
			)
			(fill yes)
			(layer "F.Fab")
		)
		(pad "1" smd rect
			(at -0.94996 -0.649986 90)
			(size 0.4318 0.508)
			(layers "F.Cu" "F.Mask" "F.Paste")
			(net "GND")
		)
		(pad "2" smd rect
			(at -0.94996 0 90)
			(size 0.4318 0.508)
			(layers "F.Cu" "F.Mask" "F.Paste")
			(net "HPDB_HSC_PWRGD")
		)
		(pad "3" smd rect
			(at -0.94996 0.649986 90)
			(size 0.4318 0.508)
			(layers "F.Cu" "F.Mask" "F.Paste")
			(net "HPDB_HSC_PWRGD_ISO")
		)
		(pad "4" smd rect
			(at 0.94996 0.649986 90)
			(size 0.4318 0.508)
			(layers "F.Cu" "F.Mask" "F.Paste")
			(net "GND")
		)
		(pad "5" smd rect
			(at 0.94996 0 90)
			(size 0.4318 0.508)
			(layers "F.Cu" "F.Mask" "F.Paste")
			(net "HPDB_HSC_PWRGD_N")
		)
		(pad "6" smd rect
			(at 0.94996 -0.649986 90)
			(size 0.4318 0.508)
			(layers "F.Cu" "F.Mask" "F.Paste")
			(net "HPDB_HSC_PWRGD_N")
		)
	)
	(footprint ""
		(layer "F.Cu")
		(at 398.893538 -393.96416)
		(property "Reference" "R1070"
			(at 0 0 0)
			(layer "F.SilkS")
			(hide yes)
			(effects
				(font
					(size 1.27 1.27)
				)
			)
		)
		(property "Value" ""
			(at 0 0 0)
			(layer "F.Fab")
			(effects
				(font
					(size 1.27 1.27)
				)
			)
		)
		(duplicate_pad_numbers_are_jumpers no)
		(fp_line
			(start -0.32512 -0.175006)
			(end 0.32512 -0.175006)
			(stroke
				(width 0.1)
				(type default)
			)
			(layer "F.Fab")
		)
		(fp_line
			(start -0.32512 0.175006)
			(end -0.32512 -0.175006)
			(stroke
				(width 0.1)
				(type default)
			)
			(layer "F.Fab")
		)
		(fp_line
			(start 0.32512 -0.175006)
			(end 0.32512 0.175006)
			(stroke
				(width 0.1)
				(type default)
			)
			(layer "F.Fab")
		)
		(fp_line
			(start 0.32512 0.175006)
			(end -0.32512 0.175006)
			(stroke
				(width 0.1)
				(type default)
			)
			(layer "F.Fab")
		)
		(pad "1" smd rect
			(at -0.2667 0)
			(size 0.3048 0.381)
			(layers "F.Cu" "F.Mask" "F.Paste")
			(net "GPIO2_RT_CPU0_P2")
		)
		(pad "2" smd rect
			(at 0.2667 0 180)
			(size 0.3048 0.381)
			(layers "F.Cu" "F.Mask" "F.Paste")
			(net "GND")
		)
	)
)
